(kicad_pcb
	(version 20260206)
	(generator "pcbnew")
	(generator_version "10.0")
	(general
		(thickness 1.6)
		(legacy_teardrops no)
	)
	(paper "A4")
	(title_block
		(title "03242023_DA0F0TMBIJ0_F0T_Motherboard_J_brd_V01_OCP.brd")
		(comment 1 "Grand Teton / footprints 155-161 of 6105")
	)
	(layers
		(0 "F.Cu" signal "TOP")
		(4 "In1.Cu" signal "GND")
		(6 "In2.Cu" signal "IN1")
		(8 "In3.Cu" signal "GND1")
		(10 "In4.Cu" signal "IN2")
		(12 "In5.Cu" signal "GND2")
		(14 "In6.Cu" signal "IN3")
		(16 "In7.Cu" signal "GND3")
		(18 "In8.Cu" signal "VCC")
		(20 "In9.Cu" signal "VCC1")
		(22 "In10.Cu" signal "GND4")
		(24 "In11.Cu" signal "IN4")
		(26 "In12.Cu" signal "GND5")
		(28 "In13.Cu" signal "IN5")
		(30 "In14.Cu" signal "GND6")
		(32 "In15.Cu" signal "IN6")
		(34 "In16.Cu" signal "GND7")
		(2 "B.Cu" signal "BOTTOM")
		(9 "F.Adhes" user "F.Adhesive")
		(11 "B.Adhes" user "B.Adhesive")
		(13 "F.Paste" user "Package Geometry/Pastemask Top")
		(15 "B.Paste" user "Package Geometry/Pastemask Bottom")
		(5 "F.SilkS" user "Ref Des/Silkscreen Top")
		(7 "B.SilkS" user "Ref Des/Silkscreen Bottom")
		(1 "F.Mask" user "Board Geometry/Soldermask Top")
		(3 "B.Mask" user "Board Geometry/Soldermask Bottom")
		(17 "Dwgs.User" user "User.Drawings")
		(19 "Cmts.User" user "User.Comments")
		(21 "Eco1.User" user "User.Eco1")
		(23 "Eco2.User" user "User.Eco2")
		(25 "Edge.Cuts" user "Board Geometry/Outline")
		(27 "Margin" user)
		(31 "F.CrtYd" user "Package Geometry/Place Bound Top")
		(29 "B.CrtYd" user "Package Geometry/Place Bound Bottom")
		(35 "F.Fab" user "Ref Des/Assembly Top")
		(33 "B.Fab" user "Ref Des/Assembly Bottom")
	)
	(footprint ""
		(layer "F.Cu")
		(at 298.472352 -354.000816 -90)
		(property "Reference" "PL34"
			(at -2.045462 -5.057648 0)
			(unlocked yes)
			(layer "F.SilkS")
			(effects
				(font
					(size 0.7874 0.5842)
					(thickness 0.1524)
				)
				(justify left)
			)
		)
		(property "Value" ""
			(at 0 0 270)
			(layer "F.Fab")
			(effects
				(font
					(size 1.27 1.27)
				)
			)
		)
		(duplicate_pad_numbers_are_jumpers no)
		(fp_line
			(start -4.99999 3.750056)
			(end -4.99999 2.2479)
			(stroke
				(width 0.1524)
				(type default)
			)
			(layer "F.SilkS")
		)
		(fp_line
			(start 0 3.750056)
			(end -4.99999 3.750056)
			(stroke
				(width 0.1524)
				(type default)
			)
			(layer "F.SilkS")
		)
		(fp_line
			(start 4.99999 3.750056)
			(end 0 3.750056)
			(stroke
				(width 0.1524)
				(type default)
			)
			(layer "F.SilkS")
		)
		(fp_line
			(start 4.99999 2.2352)
			(end 4.99999 3.750056)
			(stroke
				(width 0.1524)
				(type default)
			)
			(layer "F.SilkS")
		)
		(fp_line
			(start -4.99999 -2.2479)
			(end -4.99999 -3.750056)
			(stroke
				(width 0.1524)
				(type default)
			)
			(layer "F.SilkS")
		)
		(fp_line
			(start -4.99999 -3.750056)
			(end 4.99999 -3.750056)
			(stroke
				(width 0.1524)
				(type default)
			)
			(layer "F.SilkS")
		)
		(fp_line
			(start 4.99999 -3.750056)
			(end 4.99999 -2.2479)
			(stroke
				(width 0.1524)
				(type default)
			)
			(layer "F.SilkS")
		)
		(fp_line
			(start -4.99999 3.750056)
			(end -4.99999 -3.750056)
			(stroke
				(width 0.1)
				(type default)
			)
			(layer "F.Fab")
		)
		(fp_line
			(start 0 3.750056)
			(end -4.99999 3.750056)
			(stroke
				(width 0.1)
				(type default)
			)
			(layer "F.Fab")
		)
		(fp_line
			(start 4.99999 3.750056)
			(end 0 3.750056)
			(stroke
				(width 0.1)
				(type default)
			)
			(layer "F.Fab")
		)
		(fp_line
			(start -4.99999 -3.750056)
			(end 4.99999 -3.750056)
			(stroke
				(width 0.1)
				(type default)
			)
			(layer "F.Fab")
		)
		(fp_line
			(start 4.99999 -3.750056)
			(end 4.99999 3.750056)
			(stroke
				(width 0.1)
				(type default)
			)
			(layer "F.Fab")
		)
		(pad "1" smd rect
			(at -3.299968 0 270)
			(size 3.302 4.2164)
			(layers "F.Cu" "F.Mask" "F.Paste")
			(net "SW_PVCCFA_EHV_FIVRA_CPU0_SW2")
		)
		(pad "2" smd rect
			(at 3.299968 0 270)
			(size 3.302 4.2164)
			(layers "F.Cu" "F.Mask" "F.Paste")
			(net "PVCCFA_EHV_FIVRA_CPU0")
		)
	)
	(footprint ""
		(layer "F.Cu")
		(at 353.235514 -256.654046 -90)
		(property "Reference" "C422"
			(at 0 0 270)
			(layer "F.SilkS")
			(hide yes)
			(effects
				(font
					(size 1.27 1.27)
				)
			)
		)
		(property "Value" ""
			(at 0 0 270)
			(layer "F.Fab")
			(effects
				(font
					(size 1.27 1.27)
				)
			)
		)
		(duplicate_pad_numbers_are_jumpers no)
		(fp_line
			(start -0.7874 0.4064)
			(end -0.7874 -0.4064)
			(stroke
				(width 0.1524)
				(type default)
			)
			(layer "F.SilkS")
		)
		(fp_line
			(start 0.7874 0.4064)
			(end -0.7874 0.4064)
			(stroke
				(width 0.1524)
				(type default)
			)
			(layer "F.SilkS")
		)
		(fp_line
			(start -0.7874 -0.4064)
			(end 0.7874 -0.4064)
			(stroke
				(width 0.1524)
				(type default)
			)
			(layer "F.SilkS")
		)
		(fp_line
			(start 0.7874 -0.4064)
			(end 0.7874 0.4064)
			(stroke
				(width 0.1524)
				(type default)
			)
			(layer "F.SilkS")
		)
		(fp_line
			(start -0.67945 0.3048)
			(end -0.67945 -0.305054)
			(stroke
				(width 0.1)
				(type default)
			)
			(layer "F.Fab")
		)
		(fp_line
			(start -0.12065 0.3048)
			(end -0.67945 0.3048)
			(stroke
				(width 0.1)
				(type default)
			)
			(layer "F.Fab")
		)
		(fp_line
			(start 0.120396 0.3048)
			(end 0.120396 0.2794)
			(stroke
				(width 0.1)
				(type default)
			)
			(layer "F.Fab")
		)
		(fp_line
			(start 0.67945 0.3048)
			(end 0.120396 0.3048)
			(stroke
				(width 0.1)
				(type default)
			)
			(layer "F.Fab")
		)
		(fp_line
			(start -0.12065 0.2794)
			(end -0.12065 0.3048)
			(stroke
				(width 0.1)
				(type default)
			)
			(layer "F.Fab")
		)
		(fp_line
			(start 0.120396 0.2794)
			(end -0.12065 0.2794)
			(stroke
				(width 0.1)
				(type default)
			)
			(layer "F.Fab")
		)
		(fp_line
			(start -0.12065 -0.2794)
			(end 0.12065 -0.2794)
			(stroke
				(width 0.1)
				(type default)
			)
			(layer "F.Fab")
		)
		(fp_line
			(start 0.12065 -0.2794)
			(end 0.12065 -0.3048)
			(stroke
				(width 0.1)
				(type default)
			)
			(layer "F.Fab")
		)
		(fp_line
			(start 0.12065 -0.3048)
			(end 0.67945 -0.3048)
			(stroke
				(width 0.1)
				(type default)
			)
			(layer "F.Fab")
		)
		(fp_line
			(start 0.67945 -0.3048)
			(end 0.67945 0.3048)
			(stroke
				(width 0.1)
				(type default)
			)
			(layer "F.Fab")
		)
		(fp_line
			(start -0.67945 -0.305054)
			(end -0.12065 -0.305054)
			(stroke
				(width 0.1)
				(type default)
			)
			(layer "F.Fab")
		)
		(fp_line
			(start -0.12065 -0.305054)
			(end -0.12065 -0.2794)
			(stroke
				(width 0.1)
				(type default)
			)
			(layer "F.Fab")
		)
		(pad "1" smd circle
			(at -0.40005 0 270)
			(size 0 0)
			(layers "F.Cu" "F.Mask" "F.Paste")
			(net "PVCCFA_EHV_CPU0")
		)
		(pad "2" smd circle
			(at 0.40005 0 270)
			(size 0 0)
			(layers "F.Cu" "F.Mask" "F.Paste")
			(net "GND")
		)
	)
	(footprint ""
		(layer "F.Cu")
		(at 312.448194 -32.869886 180)
		(property "Reference" "R1454"
			(at 0 0 180)
			(layer "F.SilkS")
			(hide yes)
			(effects
				(font
					(size 1.27 1.27)
				)
			)
		)
		(property "Value" ""
			(at 0 0 180)
			(layer "F.Fab")
			(effects
				(font
					(size 1.27 1.27)
				)
			)
		)
		(duplicate_pad_numbers_are_jumpers no)
		(fp_line
			(start 0.7874 0.4064)
			(end -0.7874 0.4064)
			(stroke
				(width 0.1524)
				(type default)
			)
			(layer "F.SilkS")
		)
		(fp_line
			(start 0.7874 -0.4064)
			(end 0.7874 0.4064)
			(stroke
				(width 0.1524)
				(type default)
			)
			(layer "F.SilkS")
		)
		(fp_line
			(start -0.7874 0.4064)
			(end -0.7874 -0.4064)
			(stroke
				(width 0.1524)
				(type default)
			)
			(layer "F.SilkS")
		)
		(fp_line
			(start -0.7874 -0.4064)
			(end 0.7874 -0.4064)
			(stroke
				(width 0.1524)
				(type default)
			)
			(layer "F.SilkS")
		)
		(fp_line
			(start 0.67945 0.3048)
			(end 0.120396 0.3048)
			(stroke
				(width 0.1)
				(type default)
			)
			(layer "F.Fab")
		)
		(fp_line
			(start 0.67945 -0.3048)
			(end 0.67945 0.3048)
			(stroke
				(width 0.1)
				(type default)
			)
			(layer "F.Fab")
		)
		(fp_line
			(start 0.12065 -0.2794)
			(end 0.12065 -0.3048)
			(stroke
				(width 0.1)
				(type default)
			)
			(layer "F.Fab")
		)
		(fp_line
			(start 0.12065 -0.3048)
			(end 0.67945 -0.3048)
			(stroke
				(width 0.1)
				(type default)
			)
			(layer "F.Fab")
		)
		(fp_line
			(start 0.120396 0.3048)
			(end 0.120396 0.2794)
			(stroke
				(width 0.1)
				(type default)
			)
			(layer "F.Fab")
		)
		(fp_line
			(start 0.120396 0.2794)
			(end -0.12065 0.2794)
			(stroke
				(width 0.1)
				(type default)
			)
			(layer "F.Fab")
		)
		(fp_line
			(start -0.12065 0.3048)
			(end -0.67945 0.3048)
			(stroke
				(width 0.1)
				(type default)
			)
			(layer "F.Fab")
		)
		(fp_line
			(start -0.12065 0.2794)
			(end -0.12065 0.3048)
			(stroke
				(width 0.1)
				(type default)
			)
			(layer "F.Fab")
		)
		(fp_line
			(start -0.12065 -0.2794)
			(end 0.12065 -0.2794)
			(stroke
				(width 0.1)
				(type default)
			)
			(layer "F.Fab")
		)
		(fp_line
			(start -0.12065 -0.305054)
			(end -0.12065 -0.2794)
			(stroke
				(width 0.1)
				(type default)
			)
			(layer "F.Fab")
		)
		(fp_line
			(start -0.67945 0.3048)
			(end -0.67945 -0.305054)
			(stroke
				(width 0.1)
				(type default)
			)
			(layer "F.Fab")
		)
		(fp_line
			(start -0.67945 -0.305054)
			(end -0.12065 -0.305054)
			(stroke
				(width 0.1)
				(type default)
			)
			(layer "F.Fab")
		)
		(pad "1" smd circle
			(at -0.40005 0 180)
			(size 0 0)
			(layers "F.Cu" "F.Mask" "F.Paste")
			(net "PU_SMB_SML4_3V3AUX_PCH_SDA")
		)
		(pad "2" smd circle
			(at 0.40005 0 180)
			(size 0 0)
			(layers "F.Cu" "F.Mask" "F.Paste")
			(net "P3V3_AUX")
		)
	)
	(footprint ""
		(layer "F.Cu")
		(at 27.046428 -102.888034 180)
		(property "Reference" "C1767"
			(at 0 0 180)
			(layer "F.SilkS")
			(hide yes)
			(effects
				(font
					(size 1.27 1.27)
				)
			)
		)
		(property "Value" ""
			(at 0 0 180)
			(layer "F.Fab")
			(effects
				(font
					(size 1.27 1.27)
				)
			)
		)
		(duplicate_pad_numbers_are_jumpers no)
		(fp_line
			(start 1.524 0.762)
			(end -1.524 0.762)
			(stroke
				(width 0.1524)
				(type default)
			)
			(layer "F.SilkS")
		)
		(fp_line
			(start 1.524 -0.762)
			(end 1.524 0.762)
			(stroke
				(width 0.1524)
				(type default)
			)
			(layer "F.SilkS")
		)
		(fp_line
			(start -1.524 0.762)
			(end -1.524 -0.762)
			(stroke
				(width 0.1524)
				(type default)
			)
			(layer "F.SilkS")
		)
		(fp_line
			(start -1.524 -0.762)
			(end 1.524 -0.762)
			(stroke
				(width 0.1524)
				(type default)
			)
			(layer "F.SilkS")
		)
		(fp_line
			(start 1.1049 0.724916)
			(end 1.1049 -0.724916)
			(stroke
				(width 0.1)
				(type default)
			)
			(layer "F.Fab")
		)
		(fp_line
			(start 1.1049 -0.724916)
			(end -1.1049 -0.724916)
			(stroke
				(width 0.1)
				(type default)
			)
			(layer "F.Fab")
		)
		(fp_line
			(start -1.1049 0.724916)
			(end 1.1049 0.724916)
			(stroke
				(width 0.1)
				(type default)
			)
			(layer "F.Fab")
		)
		(fp_line
			(start -1.1049 -0.724916)
			(end -1.1049 0.724916)
			(stroke
				(width 0.1)
				(type default)
			)
			(layer "F.Fab")
		)
		(pad "1" smd rect
			(at -0.889 0)
			(size 1.016 1.27)
			(layers "F.Cu" "F.Mask" "F.Paste")
			(net "MAX11617_VREF")
		)
		(pad "2" smd rect
			(at 0.889 0)
			(size 1.016 1.27)
			(layers "F.Cu" "F.Mask" "F.Paste")
			(net "GND")
		)
	)
	(footprint ""
		(layer "F.Cu")
		(at 422.02354 -52.16652)
		(property "Reference" "U330"
			(at -1.905 -2.174748 0)
			(unlocked yes)
			(layer "F.SilkS")
			(effects
				(font
					(size 0.7874 0.5842)
					(thickness 0.1524)
				)
				(justify left)
			)
		)
		(property "Value" ""
			(at 0 0 0)
			(layer "F.Fab")
			(effects
				(font
					(size 1.27 1.27)
				)
			)
		)
		(duplicate_pad_numbers_are_jumpers no)
		(fp_line
			(start -1.759712 -1.500124)
			(end 1.759712 -1.500124)
			(stroke
				(width 0.1524)
				(type default)
			)
			(layer "F.SilkS")
		)
		(fp_line
			(start -1.759712 1.500124)
			(end -1.759712 -1.500124)
			(stroke
				(width 0.1524)
				(type default)
			)
			(layer "F.SilkS")
		)
		(fp_line
			(start 1.759712 -1.500124)
			(end 1.759712 1.500124)
			(stroke
				(width 0.1524)
				(type default)
			)
			(layer "F.SilkS")
		)
		(fp_line
			(start 1.759712 1.500124)
			(end -1.759712 1.500124)
			(stroke
				(width 0.1524)
				(type default)
			)
			(layer "F.SilkS")
		)
		(fp_line
			(start -0.700024 -1.500124)
			(end 0.700024 -1.500124)
			(stroke
				(width 0.1)
				(type default)
			)
			(layer "F.Fab")
		)
		(fp_line
			(start -0.700024 1.500124)
			(end -0.700024 -1.500124)
			(stroke
				(width 0.1)
				(type default)
			)
			(layer "F.Fab")
		)
		(fp_line
			(start 0.700024 -1.500124)
			(end 0.700024 1.500124)
			(stroke
				(width 0.1)
				(type default)
			)
			(layer "F.Fab")
		)
		(fp_line
			(start 0.700024 1.500124)
			(end -0.700024 1.500124)
			(stroke
				(width 0.1)
				(type default)
			)
			(layer "F.Fab")
		)
		(pad "1" smd rect
			(at -1.150112 -0.94996 270)
			(size 0.6604 0.9652)
			(layers "F.Cu" "F.Mask" "F.Paste")
			(net "GND")
		)
		(pad "2" smd rect
			(at -1.150112 0.94996 270)
			(size 0.6604 0.9652)
			(layers "F.Cu" "F.Mask" "F.Paste")
			(net "PWRGD_P3V3_R1")
		)
		(pad "3" smd rect
			(at 1.150112 0 270)
			(size 0.6604 0.9652)
			(layers "F.Cu" "F.Mask" "F.Paste")
			(net "P3V3")
		)
	)
	(footprint ""
		(layer "F.Cu")
		(at 120.37822 -418.399468 180)
		(property "Reference" "R3317"
			(at 0 0 180)
			(layer "F.SilkS")
			(hide yes)
			(effects
				(font
					(size 1.27 1.27)
				)
			)
		)
		(property "Value" ""
			(at 0 0 180)
			(layer "F.Fab")
			(effects
				(font
					(size 1.27 1.27)
				)
			)
		)
		(duplicate_pad_numbers_are_jumpers no)
		(fp_line
			(start 0.7874 0.4064)
			(end -0.7874 0.4064)
			(stroke
				(width 0.1524)
				(type default)
			)
			(layer "F.SilkS")
		)
		(fp_line
			(start 0.7874 -0.4064)
			(end 0.7874 0.4064)
			(stroke
				(width 0.1524)
				(type default)
			)
			(layer "F.SilkS")
		)
		(fp_line
			(start -0.7874 0.4064)
			(end -0.7874 -0.4064)
			(stroke
				(width 0.1524)
				(type default)
			)
			(layer "F.SilkS")
		)
		(fp_line
			(start -0.7874 -0.4064)
			(end 0.7874 -0.4064)
			(stroke
				(width 0.1524)
				(type default)
			)
			(layer "F.SilkS")
		)
		(fp_line
			(start 0.67945 0.3048)
			(end 0.120396 0.3048)
			(stroke
				(width 0.1)
				(type default)
			)
			(layer "F.Fab")
		)
		(fp_line
			(start 0.67945 -0.3048)
			(end 0.67945 0.3048)
			(stroke
				(width 0.1)
				(type default)
			)
			(layer "F.Fab")
		)
		(fp_line
			(start 0.12065 -0.2794)
			(end 0.12065 -0.3048)
			(stroke
				(width 0.1)
				(type default)
			)
			(layer "F.Fab")
		)
		(fp_line
			(start 0.12065 -0.3048)
			(end 0.67945 -0.3048)
			(stroke
				(width 0.1)
				(type default)
			)
			(layer "F.Fab")
		)
		(fp_line
			(start 0.120396 0.3048)
			(end 0.120396 0.2794)
			(stroke
				(width 0.1)
				(type default)
			)
			(layer "F.Fab")
		)
		(fp_line
			(start 0.120396 0.2794)
			(end -0.12065 0.2794)
			(stroke
				(width 0.1)
				(type default)
			)
			(layer "F.Fab")
		)
		(fp_line
			(start -0.12065 0.3048)
			(end -0.67945 0.3048)
			(stroke
				(width 0.1)
				(type default)
			)
			(layer "F.Fab")
		)
		(fp_line
			(start -0.12065 0.2794)
			(end -0.12065 0.3048)
			(stroke
				(width 0.1)
				(type default)
			)
			(layer "F.Fab")
		)
		(fp_line
			(start -0.12065 -0.2794)
			(end 0.12065 -0.2794)
			(stroke
				(width 0.1)
				(type default)
			)
			(layer "F.Fab")
		)
		(fp_line
			(start -0.12065 -0.305054)
			(end -0.12065 -0.2794)
			(stroke
				(width 0.1)
				(type default)
			)
			(layer "F.Fab")
		)
		(fp_line
			(start -0.67945 0.3048)
			(end -0.67945 -0.305054)
			(stroke
				(width 0.1)
				(type default)
			)
			(layer "F.Fab")
		)
		(fp_line
			(start -0.67945 -0.305054)
			(end -0.12065 -0.305054)
			(stroke
				(width 0.1)
				(type default)
			)
			(layer "F.Fab")
		)
		(pad "1" smd circle
			(at -0.40005 0 180)
			(size 0 0)
			(layers "F.Cu" "F.Mask" "F.Paste")
			(net "P3V3_AUX")
		)
		(pad "2" smd circle
			(at 0.40005 0 180)
			(size 0 0)
			(layers "F.Cu" "F.Mask" "F.Paste")
			(net "GPU_FPGA_RST_R1_BUF_N")
		)
	)
	(footprint ""
		(layer "F.Cu")
		(at 243.03863 -123.004834)
		(property "Reference" "R3201"
			(at 0 0 0)
			(layer "F.SilkS")
			(hide yes)
			(effects
				(font
					(size 1.27 1.27)
				)
			)
		)
		(property "Value" ""
			(at 0 0 0)
			(layer "F.Fab")
			(effects
				(font
					(size 1.27 1.27)
				)
			)
		)
		(duplicate_pad_numbers_are_jumpers no)
		(fp_line
			(start -0.7874 -0.4064)
			(end 0.7874 -0.4064)
			(stroke
				(width 0.1524)
				(type default)
			)
			(layer "F.SilkS")
		)
		(fp_line
			(start -0.7874 0.063754)
			(end -0.7874 -0.4064)
			(stroke
				(width 0.1524)
				(type default)
			)
			(layer "F.SilkS")
		)
		(fp_line
			(start 0.46863 0.4064)
			(end -0.45847 0.4064)
			(stroke
				(width 0.1524)
				(type default)
			)
			(layer "F.SilkS")
		)
		(fp_line
			(start 0.7874 -0.4064)
			(end 0.7874 0.053594)
			(stroke
				(width 0.1524)
				(type default)
			)
			(layer "F.SilkS")
		)
		(fp_line
			(start -0.67945 -0.305054)
			(end -0.12065 -0.305054)
			(stroke
				(width 0.1)
				(type default)
			)
			(layer "F.Fab")
		)
		(fp_line
			(start -0.67945 0.3048)
			(end -0.67945 -0.305054)
			(stroke
				(width 0.1)
				(type default)
			)
			(layer "F.Fab")
		)
		(fp_line
			(start -0.12065 -0.305054)
			(end -0.12065 -0.2794)
			(stroke
				(width 0.1)
				(type default)
			)
			(layer "F.Fab")
		)
		(fp_line
			(start -0.12065 -0.2794)
			(end 0.12065 -0.2794)
			(stroke
				(width 0.1)
				(type default)
			)
			(layer "F.Fab")
		)
		(fp_line
			(start -0.12065 0.2794)
			(end -0.12065 0.3048)
			(stroke
				(width 0.1)
				(type default)
			)
			(layer "F.Fab")
		)
		(fp_line
			(start -0.12065 0.3048)
			(end -0.67945 0.3048)
			(stroke
				(width 0.1)
				(type default)
			)
			(layer "F.Fab")
		)
		(fp_line
			(start 0.120396 0.2794)
			(end -0.12065 0.2794)
			(stroke
				(width 0.1)
				(type default)
			)
			(layer "F.Fab")
		)
		(fp_line
			(start 0.120396 0.3048)
			(end 0.120396 0.2794)
			(stroke
				(width 0.1)
				(type default)
			)
			(layer "F.Fab")
		)
		(fp_line
			(start 0.12065 -0.3048)
			(end 0.67945 -0.3048)
			(stroke
				(width 0.1)
				(type default)
			)
			(layer "F.Fab")
		)
		(fp_line
			(start 0.12065 -0.2794)
			(end 0.12065 -0.3048)
			(stroke
				(width 0.1)
				(type default)
			)
			(layer "F.Fab")
		)
		(fp_line
			(start 0.67945 -0.3048)
			(end 0.67945 0.3048)
			(stroke
				(width 0.1)
				(type default)
			)
			(layer "F.Fab")
		)
		(fp_line
			(start 0.67945 0.3048)
			(end 0.120396 0.3048)
			(stroke
				(width 0.1)
				(type default)
			)
			(layer "F.Fab")
		)
		(pad "1" smd circle
			(at -0.40005 0)
			(size 0 0)
			(layers "F.Cu" "F.Mask" "F.Paste")
			(net "CLK_100M_OCP_V3_2_D_R_DN")
		)
		(pad "2" smd circle
			(at 0.40005 0)
			(size 0 0)
			(layers "F.Cu" "F.Mask" "F.Paste")
			(net "CLK_100M_OCP_V3_2_D_DN")
		)
	)
)
